# T6G (Grand Teton) — schematic parts with pin connectivity, parts 2731–2883 of 8303; source: Cadence DE-HDL packaged netlist (pstxprt.dat, pstxnet.dat, pstchip.dat)

PC20  Q_CAP  1UF 25V 10% X6S  pkg C0402  page 226 : 1 = PVDD18_S5_P1_VCC ; 2 = GND
PC21  Q_CAP  0.1UF 25V 10% X7R  pkg 0402  page 226 : 1 = PVDD18_S5_P1 ; 2 = GND
PC22  Q_CAP  1UF 25V 10% X6S  pkg C0402  page 226 : 1 = SW_P12V_AUX_PVDD18_S5_P1_FLT ; 2 = GND
PC27  Q_CAP  22UF 16V 20% X6S  pkg C0805  page 225 : 1 = SW_P12V_AUX_PVDD11_S3_P1_FLT ; 2 = GND
PC29  Q_CAP  0.1UF 25V 10% X7R  pkg 0402  page 217 : 1 = PVDDCR_CPU1_P1_VCC ; 2 = GND
PC60  Q_CAP  22UF 16V 20% X6S  pkg C0805  page 226 : 1 = SW_P12V_AUX_PVDD18_S5_P1_FLT ; 2 = GND
PC61  Q_CAP  22UF 16V 20% X6S  pkg C0805  page 226 : 1 = SW_P12V_AUX_PVDD18_S5_P1_FLT ; 2 = GND
PC62  Q_CAP  0.1UF 25V 10% X7R  pkg 0402  page 226 : 1 = PVDD18_S5_P1_REF ; 2 = PVDD18_SS_P1_RGND
PC64  Q_CAP  220PF 50V 10% X7R  pkg 0402  page 226 : 1 = PVDD18_S5_P1_FB ; 2 = PVDD18_S5_P1_FB_RC
PC65  Q_CAP  22UF 4V 20% X6S  pkg C0805  page 226 : 1 = PVDD18_S5_P1 ; 2 = GND
PC67  Q_CAP  0.1UF 25V 10% X7R  pkg 0402  page 200 : 1 = PVDDCR_CPU1_P0_VMON ; 2 = GND
PC68  Q_CAP  3300PF 50V 10% X7R  pkg 0402  page 200 : 1 = VSENSE_PVDDCR_CPU1_P0_VSEN0 ; 2 = VSENSE_VSS_SENSE_C_P0
PC71  Q_CAP  3300PF 50V 10% X7R  pkg 0402  page 200 : 1 = VSENSE_PVDDIO_P0_VSEN1 ; 2 = VSENSE_VSS_SENSE_B_P0
PC73  Q_CAP  1UF 6.3V 10% X7R  pkg 0402  page 200 : 1 = PVDD18_S5_P0 ; 2 = GND
PC74  Q_CAP  0.1UF 25V 10% X7R  pkg 0402  page 200 : 1 = PVDDCR_CPU1_P0_VINSEN ; 2 = GND
PC75  Q_CAP  1UF 16V 10% X6S  pkg C0402  page 200 : 1 = PVDDCR_CPU1_P0_VCC ; 2 = GND
PC76  Q_CAP  10UF 6.3V 20% X6S  pkg C0402  page 200 : 1 = PVDDCR_CPU1_P0_VCCS ; 2 = GND
PC77  Q_CAP  470PF 50V 10% X7R  pkg 0402  page 200 : 1 = PVDDIO_P0_TEMP1 ; 2 = GND
PC78  Q_CAP  470PF 50V 10% X7R  pkg 0402  page 200 : 1 = PVDDCR_CPU1_P0_TEMP0 ; 2 = GND
PC79  Q_CAP  2.2UF 10V 10% X6S  pkg C0402  page 201 : 1 = PVDDCR_CPU1_P0_VCC1 ; 2 = GND
PC80  Q_CAP  2.2UF 10V 10% X6S  pkg C0402  page 201 : 1 = PVDDCR_CPU1_P0_VCC2 ; 2 = GND
PC81  Q_CAP  22UF 16V 20% X6S  pkg C0805  page 209 : 1 = SW_P12V_AUX_PVDD18_S5_P0_FLT ; 2 = GND
PC81_C1P0_1  Q_CAP  2.2UF 10V 10% X6S  pkg C0402  page 201 : 1 = PVDDCR_CPU1_P0_PVCC ; 2 = GND
PC82_C1P0_2  Q_CAP  2.2UF 10V 10% X6S  pkg C0402  page 201 : 1 = PVDDCR_CPU1_P0_PVCC ; 2 = GND
PC83  Q_CAP  22UF 4V 20% X6S  pkg C0805  page 226 : 1 = PVDD18_S5_P1 ; 2 = GND
PC83_2  Q_CAP  0.1UF 25V 10% X7R  pkg 0402  page 201 : 1 = PVDDCR_CPU1_P0_VCCS ; 2 = GND
PC84  Q_CAP  22UF 4V 20% X6S  pkg C0805  page 226 : 1 = PVDD18_S5_P1 ; 2 = GND
PC84_1  Q_CAP  0.1UF 25V 10% X7R  pkg 0402  page 201 : 1 = PVDDCR_CPU1_P0_VCCS ; 2 = GND
PC85  Q_CAP  0.1UF 25V 10% X7R  pkg 0402  page 201 : 1 = P12V_AUX ; 2 = GND
PC85_1  Q_CAP  0.1UF 25V 10% X7R  pkg 0402  page 201 : 1 = SW_P12V_AUX_PVDDCR_CPU1_P0_FLT ; 2 = GND
PC86_2  Q_CAP  0.1UF 25V 10% X7R  pkg 0402  page 201 : 1 = SW_P12V_AUX_PVDDCR_CPU1_P0_FLT ; 2 = GND
PC87  Q_CAP  22UF 4V 20% EMPTY  pkg C0805  page 226 : 1 = PVDD18_S5_P1 ; 2 = GND
PC87_1  Q_CAP  1UF 25V 10% X6S  pkg C0402  page 201 : 1 = SW_P12V_AUX_PVDDCR_CPU1_P0_FLT ; 2 = GND
PC88  Q_CAP  22UF 4V 20% EMPTY  pkg C0805  page 226 : 1 = PVDD18_S5_P1 ; 2 = GND
PC88_2  Q_CAP  1UF 25V 10% X6S  pkg C0402  page 201 : 1 = SW_P12V_AUX_PVDDCR_CPU1_P0_FLT ; 2 = GND
PC89  Q_CAPP  390UF 2.5V 20% ALUM  pkg SMLF  page 226 : 1 = PVDD18_S5_P1 ; 2 = GND
PC89_1  Q_CAP  22UF 16V 20% X6S  pkg C0805  page 201 : 1 = SW_P12V_AUX_PVDDCR_CPU1_P0_FLT ; 2 = GND
PC90_2  Q_CAP  22UF 16V 20% X6S  pkg C0805  page 201 : 1 = SW_P12V_AUX_PVDDCR_CPU1_P0_FLT ; 2 = GND
PC91_1  Q_CAP  22UF 16V 20% X6S  pkg C0805  page 201 : 1 = SW_P12V_AUX_PVDDCR_CPU1_P0_FLT ; 2 = GND
PC92  Q_CAP  0.22UF 16V 10% X7R  pkg 0402  page 201 : 1 = SW_PVDDCR_CPU1_P0_BOOT1_R ; 2 = SW_PVDDCR_CPU1_P0_BOOTR1
PC93  Q_CAP  0.1UF 25V 10% X7R  pkg 0402  page 217 : 1 = PVDDCR_CPU1_P1_VCCS ; 2 = GND
PC93_2  Q_CAP  22UF 16V 20% X6S  pkg C0805  page 201 : 1 = SW_P12V_AUX_PVDDCR_CPU1_P0_FLT ; 2 = GND
PC94  Q_CAP  0.22UF 16V 10% X7R  pkg 0402  page 201 : 1 = SW_PVDDCR_CPU1_P0_BOOT2_R ; 2 = SW_PVDDCR_CPU1_P0_BOOTR2
PC95  Q_CAP  0.1UF 25V 10% X7R  pkg 0402  page 224 : 1 = PVDD11_S3_P1_VCC ; 2 = GND
PC95_1  Q_CAP  22UF 16V 20% X6S  pkg C0805  page 201 : 1 = SW_P12V_AUX_PVDDCR_CPU1_P0_FLT ; 2 = GND
PC96  Q_CAP  0.1UF 25V 10% X7R  pkg 0402  page 224 : 1 = PVDD11_S3_P1_VCCS ; 2 = GND
PC96_2  Q_CAP  22UF 16V 20% X6S  pkg C0805  page 201 : 1 = SW_P12V_AUX_PVDDCR_CPU1_P0_FLT ; 2 = GND
PC97  Q_CAPP  220UF 4V 20% SPCAP  pkg SMLF  page 201 : 1 = PVDDCR_CPU1_P0 ; 2 = GND
PC98  Q_CAPP  220UF 4V 20% SPCAP  pkg SMLF  page 201 : 1 = PVDDCR_CPU1_P0 ; 2 = GND
PC99  Q_CAP  0.1UF 25V 10% X7R  pkg 0402  page 201 : 1 = PVDDCR_CPU1_P0 ; 2 = GND
PC100  Q_CAPP  220UF 4V 20% SPCAP  pkg SMLF  page 201 : 1 = PVDDCR_CPU1_P0 ; 2 = GND
PC101  Q_CAPP  270UF 16V 20% OSCON  pkg THLF  page 201 : 1 = SW_P12V_AUX_PVDDCR_CPU1_P0_FLT ; 2 = GND
PC102  Q_CAPP  220UF 4V 20% SPCAP  pkg SMLF  page 201 : 1 = PVDDCR_CPU1_P0 ; 2 = GND
PC102_1  Q_CAP  22UF 4V 20% X6S  pkg C0805  page 201 : 1 = PVDDCR_CPU1_P0 ; 2 = GND
PC103  Q_CAPP  220UF 4V 20% SPCAP  pkg SMLF  page 201 : 1 = PVDDCR_CPU1_P0 ; 2 = GND
PC104  Q_CAPP  270UF 16V 20% OSCON  pkg THLF  page 201 : 1 = SW_P12V_AUX_PVDDCR_CPU1_P0_FLT ; 2 = GND
PC105  Q_CAPP  220UF 4V 20% SPCAP  pkg SMLF  page 211 : 1 = PVDDCR_CPU0_P1 ; 2 = GND
PC105_1  Q_CAP  22UF 4V 20% X6S  pkg C0805  page 201 : 1 = PVDDCR_CPU1_P0 ; 2 = GND
PC106  Q_CAPP  220UF 4V 20% SPCAP  pkg SMLF  page 218 : 1 = PVDDCR_CPU1_P1 ; 2 = GND
PC106_2  Q_CAP  22UF 4V 20% X6S  pkg C0805  page 201 : 1 = PVDDCR_CPU1_P0 ; 2 = GND
PC107  Q_CAP  0.1UF 25V 10% X7R  pkg 0402  page 205 : 1 = PVDDIO_P0 ; 2 = GND
PC108  Q_CAPP  220UF 4V 20% SPCAP  pkg SMLF  page 194 : 1 = PVDDCR_CPU0_P0 ; 2 = GND
PC108_2  Q_CAP  22UF 4V 20% X6S  pkg C0805  page 201 : 1 = PVDDCR_CPU1_P0 ; 2 = GND
PC109  Q_CAP  2.2UF 10V 10% X6S  pkg C0402  page 202 : 1 = PVDDCR_CPU1_P0_VCC4 ; 2 = GND
PC110  Q_CAP  2.2UF 10V 10% X6S  pkg C0402  page 202 : 1 = PVDDCR_CPU1_P0_VCC3 ; 2 = GND
PC111  Q_CAP  22UF 16V 20% X6S  pkg C0805  page 209 : 1 = SW_P12V_AUX_PVDD18_S5_P0_FLT ; 2 = GND
PC111_6  Q_CAP  0.1UF 25V 10% X7R  pkg 0402  page 203 : 1 = PVDDCR_CPU1_P0_VCCS ; 2 = GND
PC111_C1P0_4  Q_CAP  2.2UF 10V 10% X6S  pkg C0402  page 202 : 1 = PVDDCR_CPU1_P0_PVCC ; 2 = GND
PC112  Q_CAP  2.2UF 10V 10% X6S  pkg C0402  page 203 : 1 = PVDDCR_CPU1_P0_VCC6 ; 2 = GND
PC112_C1P0_3  Q_CAP  2.2UF 10V 10% X6S  pkg C0402  page 202 : 1 = PVDDCR_CPU1_P0_PVCC ; 2 = GND
PC113  Q_CAP  0.1UF 25V 10% X7R  pkg 0402  page 209 : 1 = PVDD18_S5_P0_REF ; 2 = PVDD18_S5_P0_RGND
PC113_4  Q_CAP  0.1UF 25V 10% X7R  pkg 0402  page 202 : 1 = PVDDCR_CPU1_P0_VCCS ; 2 = GND
PC113_C1P0_6  Q_CAP  2.2UF 10V 10% X6S  pkg C0402  page 203 : 1 = PVDDCR_CPU1_P0_PVCC ; 2 = GND
PC114  Q_CAP  22UF 4V 20% X6S  pkg C0805  page 209 : 1 = PVDD18_S5_P0 ; 2 = GND
PC114_3  Q_CAP  0.1UF 25V 10% X7R  pkg 0402  page 202 : 1 = PVDDCR_CPU1_P0_VCCS ; 2 = GND
PC114_6  Q_CAP  0.1UF 25V 10% X7R  pkg 0402  page 203 : 1 = SW_P12V_AUX_PVDDCR_CPU1_P0_FLT ; 2 = GND
PC115  Q_CAPP  390UF 2.5V 20% ALUM  pkg SMLF  page 209 : 1 = PVDD18_S5_P0 ; 2 = GND
PC115_4  Q_CAP  0.1UF 25V 10% X7R  pkg 0402  page 202 : 1 = SW_P12V_AUX_PVDDCR_CPU1_P0_FLT ; 2 = GND
PC115_6  Q_CAP  1UF 25V 10% X6S  pkg C0402  page 203 : 1 = SW_P12V_AUX_PVDDCR_CPU1_P0_FLT ; 2 = GND
PC116_3  Q_CAP  0.1UF 25V 10% X7R  pkg 0402  page 202 : 1 = SW_P12V_AUX_PVDDCR_CPU1_P0_FLT ; 2 = GND
PC116_6  Q_CAP  22UF 16V 20% X6S  pkg C0805  page 203 : 1 = SW_P12V_AUX_PVDDCR_CPU1_P0_FLT ; 2 = GND
PC117  Q_CAP  0.22UF 16V 10% X7R  pkg 0402  page 203 : 1 = SW_PVDDCR_CPU1_P0_BOOT6_R ; 2 = SW_PVDDCR_CPU1_P0_BOOTR6
PC117_4  Q_CAP  1UF 25V 10% X6S  pkg C0402  page 202 : 1 = SW_P12V_AUX_PVDDCR_CPU1_P0_FLT ; 2 = GND
PC118  Q_CAP  1UF 25V 10% X6S  pkg C0402  page 192 : 1 = PVDD_33_S5_VCC ; 2 = GND
PC118_3  Q_CAP  1UF 25V 10% X6S  pkg C0402  page 202 : 1 = SW_P12V_AUX_PVDDCR_CPU1_P0_FLT ; 2 = GND
PC118_6  Q_CAP  22UF 16V 20% X6S  pkg C0805  page 203 : 1 = SW_P12V_AUX_PVDDCR_CPU1_P0_FLT ; 2 = GND
PC119  Q_CAP  22UF 16V 20% X6S  pkg C0805  page 192 : 1 = SW_P12V_AUX_PVDD_33_S5_FLT ; 2 = GND
PC119_4  Q_CAP  22UF 16V 20% X6S  pkg C0805  page 202 : 1 = SW_P12V_AUX_PVDDCR_CPU1_P0_FLT ; 2 = GND
PC119_6  Q_CAP  22UF 16V 20% X6S  pkg C0805  page 203 : 1 = SW_P12V_AUX_PVDDCR_CPU1_P0_FLT ; 2 = GND
PC120  Q_CAP  22UF 16V 20% X6S  pkg C0805  page 192 : 1 = SW_P12V_AUX_PVDD_33_S5_FLT ; 2 = GND
PC120_3  Q_CAP  22UF 16V 20% X6S  pkg C0805  page 202 : 1 = SW_P12V_AUX_PVDDCR_CPU1_P0_FLT ; 2 = GND
PC120_6  Q_CAP  22UF 4V 20% X6S  pkg C0805  page 203 : 1 = PVDDCR_CPU1_P0 ; 2 = GND
PC121  Q_CAP  0.22UF 16V 10% X7R  pkg 0402  page 202 : 1 = SW_PVDDCR_CPU1_P0_BOOT4_R ; 2 = SW_PVDDCR_CPU1_P0_BOOTR4
PC122  Q_CAP  0.22UF 16V 10% X7R  pkg 0402  page 202 : 1 = SW_PVDDCR_CPU1_P0_BOOT3_R ; 2 = SW_PVDDCR_CPU1_P0_BOOTR3
PC123  Q_CAP  22UF 16V 20% X6S  pkg C0805  page 192 : 1 = SW_P12V_AUX_PVDD_33_S5_FLT ; 2 = GND
PC123_4  Q_CAP  22UF 16V 20% X6S  pkg C0805  page 202 : 1 = SW_P12V_AUX_PVDDCR_CPU1_P0_FLT ; 2 = GND
PC123_6  Q_CAP  22UF 4V 20% X6S  pkg C0805  page 203 : 1 = PVDDCR_CPU1_P0 ; 2 = GND
PC124_3  Q_CAP  22UF 16V 20% X6S  pkg C0805  page 202 : 1 = SW_P12V_AUX_PVDDCR_CPU1_P0_FLT ; 2 = GND
PC124_6  Q_CAP  0.1UF 25V 10% X7R  pkg 0402  page 213 : 1 = PVDDCR_CPU0_P1_VCCS ; 2 = GND
PC125  Q_CAP  2.2UF 10V 10% X6S  pkg C0402  page 213 : 1 = PVDDCR_CPU0_P1_VCC6 ; 2 = GND
PC125_4  Q_CAP  22UF 16V 20% X6S  pkg C0805  page 202 : 1 = SW_P12V_AUX_PVDDCR_CPU1_P0_FLT ; 2 = GND
PC126  Q_CAP  1UF 25V 10% X6S  pkg C0402  page 192 : 1 = SW_P12V_AUX_PVDD_33_S5_FLT ; 2 = GND
PC126_3  Q_CAP  22UF 16V 20% X6S  pkg C0805  page 202 : 1 = SW_P12V_AUX_PVDDCR_CPU1_P0_FLT ; 2 = GND
PC126_C0P1_6  Q_CAP  2.2UF 10V 10% X6S  pkg C0402  page 213 : 1 = PVDDCR_CPU0_P1_PVCC ; 2 = GND
PC127  Q_CAP  0.1UF 25V 10% X7R  pkg 0402  page 192 : 1 = PVDD_33_S5_REF ; 2 = GND
PC127_4  Q_CAP  22UF 4V 20% X6S  pkg C0805  page 202 : 1 = PVDDCR_CPU1_P0 ; 2 = GND
PC127_6  Q_CAP  0.1UF 25V 10% X7R  pkg 0402  page 213 : 1 = SW_P12V_AUX_PVDDCR_CPU0_P1_FLT ; 2 = GND
PC128  Q_CAP  0.1UF 25V 10% X7R  pkg 0402  page 192 : 1 = SW_PVDD_33_S5_BST_R ; 2 = SW_PVDD_33_S5_SW
PC128_4  Q_CAP  22UF 4V 20% X6S  pkg C0805  page 202 : 1 = PVDDCR_CPU1_P0 ; 2 = GND
PC128_6  Q_CAP  1UF 25V 10% X6S  pkg C0402  page 213 : 1 = SW_P12V_AUX_PVDDCR_CPU0_P1_FLT ; 2 = GND
PC129  Q_CAP  22UF 16V 20% X6S  pkg C0805  page 192 : 1 = PVDD_33_S5 ; 2 = GND
PC129_3  Q_CAP  22UF 4V 20% X6S  pkg C0805  page 202 : 1 = PVDDCR_CPU1_P0 ; 2 = GND
PC129_6  Q_CAP  22UF 16V 20% X6S  pkg C0805  page 213 : 1 = SW_P12V_AUX_PVDDCR_CPU0_P1_FLT ; 2 = GND
PC130  Q_CAP  22UF 16V 20% X6S  pkg C0805  page 192 : 1 = PVDD_33_S5 ; 2 = GND
PC130_3  Q_CAP  22UF 4V 20% X6S  pkg C0805  page 202 : 1 = PVDDCR_CPU1_P0 ; 2 = GND
PC130_6  Q_CAP  22UF 16V 20% X6S  pkg C0805  page 213 : 1 = SW_P12V_AUX_PVDDCR_CPU0_P1_FLT ; 2 = GND
PC131  Q_CAP  2.2UF 10V 10% X6S  pkg C0402  page 203 : 1 = PVDDCR_CPU1_P0_VCC5 ; 2 = GND
PC132  Q_CAP  100PF 50V 5% NPO  pkg 0402  page 192 : 1 = PVDD_33_S5_FB ; 2 = PVDD_33_S5
PC132_5  Q_CAP  0.1UF 25V 10% X7R  pkg 0402  page 203 : 1 = PVDDCR_CPU1_P0_VCCS ; 2 = GND
PC132_6  Q_CAP  22UF 16V 20% X6S  pkg C0805  page 213 : 1 = SW_P12V_AUX_PVDDCR_CPU0_P1_FLT ; 2 = GND
PC133  Q_CAP  0.22UF 16V 10% X7R  pkg 0402  page 213 : 1 = SW_PVDDCR_CPU0_P1_BOOT6_RC ; 2 = SW_PVDDCR_CPU0_P1_PH6
PC133_C1P0_5  Q_CAP  2.2UF 10V 10% X6S  pkg C0402  page 203 : 1 = PVDDCR_CPU1_P0_PVCC ; 2 = GND
PC134  Q_CAP  22UF 16V 20% X6S  pkg C0805  page 192 : 1 = PVDD_33_S5 ; 2 = GND
PC134_5  Q_CAP  0.1UF 25V 10% X7R  pkg 0402  page 203 : 1 = SW_P12V_AUX_PVDDCR_CPU1_P0_FLT ; 2 = GND
PC134_6  Q_CAP  22UF 4V 20% X6S  pkg C0805  page 213 : 1 = PVDDCR_CPU0_P1 ; 2 = GND
PC135  Q_CAP  22UF 16V 20% X6S  pkg C0805  page 192 : 1 = PVDD_33_S5 ; 2 = GND
PC135_5  Q_CAP  1UF 25V 10% X6S  pkg C0402  page 203 : 1 = SW_P12V_AUX_PVDDCR_CPU1_P0_FLT ; 2 = GND
PC135_6  Q_CAP  22UF 4V 20% X6S  pkg C0805  page 213 : 1 = PVDDCR_CPU0_P1 ; 2 = GND
PC136  Q_CAP  0.1UF 25V 10% X7R  pkg 0402  page 192 : 1 = PVDD_33_S5 ; 2 = GND
PC136_5  Q_CAP  22UF 16V 20% X6S  pkg C0805  page 203 : 1 = SW_P12V_AUX_PVDDCR_CPU1_P0_FLT ; 2 = GND
PC136_6  Q_CAP  0.1UF 25V 10% X7R  pkg 0402  page 220 : 1 = PVDDCR_CPU1_P1_VCCS ; 2 = GND
PC137  Q_CAP  0.22UF 16V 10% X7R  pkg 0402  page 203 : 1 = SW_PVDDCR_CPU1_P0_BOOT5_R ; 2 = SW_PVDDCR_CPU1_P0_BOOTR5
PC138  Q_CAP  2.2UF 10V 10% X6S  pkg C0402  page 220 : 1 = PVDDCR_CPU1_P1_VCC6 ; 2 = GND
PC138_5  Q_CAP  22UF 16V 20% X6S  pkg C0805  page 203 : 1 = SW_P12V_AUX_PVDDCR_CPU1_P0_FLT ; 2 = GND
PC139_5  Q_CAP  22UF 16V 20% X6S  pkg C0805  page 203 : 1 = SW_P12V_AUX_PVDDCR_CPU1_P0_FLT ; 2 = GND
PC139_C1P1_6  Q_CAP  2.2UF 10V 10% X6S  pkg C0402  page 220 : 1 = PVDDCR_CPU1_P1_PVCC ; 2 = GND
PC140_5  Q_CAP  22UF 4V 20% X6S  pkg C0805  page 203 : 1 = PVDDCR_CPU1_P0 ; 2 = GND
PC140_6  Q_CAP  1UF 25V 10% X6S  pkg C0402  page 220 : 1 = SW_P12V_AUX_PVDDCR_CPU1_P1_FLT ; 2 = GND
PC141  Q_CAP  560PF 50V 10% EMPTY  pkg C0402  page 215 : 1 = SW_PVDDCR_SOC_P1_SW1 ; 2 = SW_PVDDCR_SOC_P1_SW1_RC
PC141_5  Q_CAP  22UF 4V 20% X6S  pkg C0805  page 203 : 1 = PVDDCR_CPU1_P0 ; 2 = GND
PC141_6  Q_CAP  0.1UF 25V 10% X7R  pkg 0402  page 220 : 1 = SW_P12V_AUX_PVDDCR_CPU1_P1_FLT ; 2 = GND
PC142  Q_CAP  2.2UF 10V 10% X6S  pkg C0402  page 205 : 1 = PVDDIO_P0_VCC2 ; 2 = GND
PC143  Q_CAP  2.2UF 10V 10% X6S  pkg C0402  page 205 : 1 = PVDDIO_P0_VCC1 ; 2 = GND
PC144_6  Q_CAP  22UF 16V 20% X6S  pkg C0805  page 220 : 1 = SW_P12V_AUX_PVDDCR_CPU1_P1_FLT ; 2 = GND
PC144_IOP0_2  Q_CAP  2.2UF 10V 10% X6S  pkg C0402  page 205 : 1 = PVDDCR_CPU1_P0_PVCC ; 2 = GND
PC145_6  Q_CAP  22UF 16V 20% X6S  pkg C0805  page 220 : 1 = SW_P12V_AUX_PVDDCR_CPU1_P1_FLT ; 2 = GND
PC145_7  Q_CAP  0.1UF 25V 10% X7R  pkg 0402  page 205 : 1 = PVDDCR_CPU1_P0_VCCS ; 2 = GND
PC146  Q_CAP  0.22UF 16V 10% X7R  pkg 0402  page 220 : 1 = SW_PVDDCR_CPU1_P1_BOOT6_R ; 2 = SW_PVDDCR_CPU1_P1_BOOTR6
PC146_8  Q_CAP  0.1UF 25V 10% X7R  pkg 0402  page 205 : 1 = PVDDCR_CPU1_P0_VCCS ; 2 = GND
PC147_6  Q_CAP  22UF 16V 20% X6S  pkg C0805  page 220 : 1 = SW_P12V_AUX_PVDDCR_CPU1_P1_FLT ; 2 = GND
PC147_IOP0_1  Q_CAP  2.2UF 10V 10% X6S  pkg C0402  page 205 : 1 = PVDDCR_CPU1_P0_PVCC ; 2 = GND
PC148  Q_CAP  0.1UF 25V 10% X7R  pkg 0402  page 205 : 1 = P12V_AUX ; 2 = GND
PC148_1  Q_CAP  0.1UF 25V 10% X7R  pkg 0402  page 205 : 1 = SW_P12V_AUX_PVDDIO_P0_FLT ; 2 = GND
